# S9S_MB_2U (Grand Teton) — schematic netlist excerpt (pin names and nets, part order shuffled) for the footprints in the layout excerpt that follows; sources: Cadence DE-HDL packaged netlist, KiCad conversion of 03242023_DA0F0TMBIJ0_F0T_Motherboard_J_brd_V01_OCP.brd

PR1771  Q_RES  3.3 1% CHIP  pkg 0402LF  page 269 : A = SW_PVCCIN_CPU0_BOOT5 ; B = SW_PVCCIN_CPU0_BOOT5_R
D68  Q_LED  IC  pkg SMLF  page 256 : A = LED_RST_PLD_CPU0_DRAM_GH_N ; C = LED_RST_PLD_CPU0_DRAM_GH_N_D

(kicad_pcb
	(version 20260206)
	(generator "pcbnew")
	(generator_version "10.0")
	(general
		(thickness 1.6)
		(legacy_teardrops no)
	)
	(paper "A4")
	(title_block
		(title "03242023_DA0F0TMBIJ0_F0T_Motherboard_J_brd_V01_OCP.brd")
		(comment 1 "Grand Teton / footprints 1268-1269 of 6105")
	)
	(layers
		(0 "F.Cu" signal "TOP")
		(4 "In1.Cu" signal "GND")
		(6 "In2.Cu" signal "IN1")
		(8 "In3.Cu" signal "GND1")
		(10 "In4.Cu" signal "IN2")
		(12 "In5.Cu" signal "GND2")
		(14 "In6.Cu" signal "IN3")
		(16 "In7.Cu" signal "GND3")
		(18 "In8.Cu" signal "VCC")
		(20 "In9.Cu" signal "VCC1")
		(22 "In10.Cu" signal "GND4")
		(24 "In11.Cu" signal "IN4")
		(26 "In12.Cu" signal "GND5")
		(28 "In13.Cu" signal "IN5")
		(30 "In14.Cu" signal "GND6")
		(32 "In15.Cu" signal "IN6")
		(34 "In16.Cu" signal "GND7")
		(2 "B.Cu" signal "BOTTOM")
		(9 "F.Adhes" user "F.Adhesive")
		(11 "B.Adhes" user "B.Adhesive")
		(13 "F.Paste" user "Package Geometry/Pastemask Top")
		(15 "B.Paste" user "Package Geometry/Pastemask Bottom")
		(5 "F.SilkS" user "Ref Des/Silkscreen Top")
		(7 "B.SilkS" user "Ref Des/Silkscreen Bottom")
		(1 "F.Mask" user "Board Geometry/Soldermask Top")
		(3 "B.Mask" user "Board Geometry/Soldermask Bottom")
		(17 "Dwgs.User" user "User.Drawings")
		(19 "Cmts.User" user "User.Comments")
		(21 "Eco1.User" user "User.Eco1")
		(23 "Eco2.User" user "User.Eco2")
		(25 "Edge.Cuts" user "Board Geometry/Outline")
		(27 "Margin" user)
		(31 "F.CrtYd" user "Package Geometry/Place Bound Top")
		(29 "B.CrtYd" user "Package Geometry/Place Bound Bottom")
		(35 "F.Fab" user "Ref Des/Assembly Top")
		(33 "B.Fab" user "Ref Des/Assembly Bottom")
	)
	(footprint ""
		(layer "F.Cu")
		(at 378.338842 -341.729822 90)
		(property "Reference" "PR1771"
			(at 0 0 90)
			(layer "F.SilkS")
			(hide yes)
			(effects
				(font
					(size 1.27 1.27)
				)
			)
		)
		(property "Value" ""
			(at 0 0 90)
			(layer "F.Fab")
			(effects
				(font
					(size 1.27 1.27)
				)
			)
		)
		(duplicate_pad_numbers_are_jumpers no)
		(fp_line
			(start 0.7874 -0.4064)
			(end 0.7874 0.4064)
			(stroke
				(width 0.1524)
				(type default)
			)
			(layer "F.SilkS")
		)
		(fp_line
			(start -0.7874 -0.4064)
			(end 0.7874 -0.4064)
			(stroke
				(width 0.1524)
				(type default)
			)
			(layer "F.SilkS")
		)
		(fp_line
			(start 0.7874 0.4064)
			(end -0.7874 0.4064)
			(stroke
				(width 0.1524)
				(type default)
			)
			(layer "F.SilkS")
		)
		(fp_line
			(start -0.7874 0.4064)
			(end -0.7874 -0.4064)
			(stroke
				(width 0.1524)
				(type default)
			)
			(layer "F.SilkS")
		)
		(fp_line
			(start -0.12065 -0.305054)
			(end -0.12065 -0.2794)
			(stroke
				(width 0.1)
				(type default)
			)
			(layer "F.Fab")
		)
		(fp_line
			(start -0.67945 -0.305054)
			(end -0.12065 -0.305054)
			(stroke
				(width 0.1)
				(type default)
			)
			(layer "F.Fab")
		)
		(fp_line
			(start 0.67945 -0.3048)
			(end 0.67945 0.3048)
			(stroke
				(width 0.1)
				(type default)
			)
			(layer "F.Fab")
		)
		(fp_line
			(start 0.12065 -0.3048)
			(end 0.67945 -0.3048)
			(stroke
				(width 0.1)
				(type default)
			)
			(layer "F.Fab")
		)
		(fp_line
			(start 0.12065 -0.2794)
			(end 0.12065 -0.3048)
			(stroke
				(width 0.1)
				(type default)
			)
			(layer "F.Fab")
		)
		(fp_line
			(start -0.12065 -0.2794)
			(end 0.12065 -0.2794)
			(stroke
				(width 0.1)
				(type default)
			)
			(layer "F.Fab")
		)
		(fp_line
			(start 0.120396 0.2794)
			(end -0.12065 0.2794)
			(stroke
				(width 0.1)
				(type default)
			)
			(layer "F.Fab")
		)
		(fp_line
			(start -0.12065 0.2794)
			(end -0.12065 0.3048)
			(stroke
				(width 0.1)
				(type default)
			)
			(layer "F.Fab")
		)
		(fp_line
			(start 0.67945 0.3048)
			(end 0.120396 0.3048)
			(stroke
				(width 0.1)
				(type default)
			)
			(layer "F.Fab")
		)
		(fp_line
			(start 0.120396 0.3048)
			(end 0.120396 0.2794)
			(stroke
				(width 0.1)
				(type default)
			)
			(layer "F.Fab")
		)
		(fp_line
			(start -0.12065 0.3048)
			(end -0.67945 0.3048)
			(stroke
				(width 0.1)
				(type default)
			)
			(layer "F.Fab")
		)
		(fp_line
			(start -0.67945 0.3048)
			(end -0.67945 -0.305054)
			(stroke
				(width 0.1)
				(type default)
			)
			(layer "F.Fab")
		)
		(pad "1" smd circle
			(at -0.40005 0 90)
			(size 0 0)
			(layers "F.Cu" "F.Mask" "F.Paste")
			(net "SW_PVCCIN_CPU0_BOOT5")
		)
		(pad "2" smd circle
			(at 0.40005 0 90)
			(size 0 0)
			(layers "F.Cu" "F.Mask" "F.Paste")
			(net "SW_PVCCIN_CPU0_BOOT5_R")
		)
	)
	(footprint ""
		(layer "F.Cu")
		(at 71.380096 -70.78599)
		(property "Reference" "D68"
			(at -37.474906 50.178462 90)
			(unlocked yes)
			(layer "F.SilkS")
			(effects
				(font
					(size 0.635 0.4064)
					(thickness 0.1524)
				)
				(justify left)
			)
		)
		(property "Value" ""
			(at 0 0 0)
			(layer "F.Fab")
			(effects
				(font
					(size 1.27 1.27)
				)
			)
		)
		(duplicate_pad_numbers_are_jumpers no)
		(fp_line
			(start -0.90678 0.4826)
			(end -0.90678 -0.4699)
			(stroke
				(width 0.1524)
				(type default)
			)
			(layer "F.SilkS")
		)
		(fp_line
			(start -0.89408 -0.4826)
			(end 0.90678 -0.4826)
			(stroke
				(width 0.1524)
				(type default)
			)
			(layer "F.SilkS")
		)
		(fp_line
			(start -0.79248 -0.4826)
			(end 1.03378 -0.4826)
			(stroke
				(width 0.1524)
				(type default)
			)
			(layer "F.SilkS")
		)
		(fp_line
			(start -0.64008 -0.4826)
			(end 1.16078 -0.4826)
			(stroke
				(width 0.1524)
				(type default)
			)
			(layer "F.SilkS")
		)
		(fp_line
			(start 0.90678 -0.4826)
			(end 0.90678 0.4826)
			(stroke
				(width 0.1524)
				(type default)
			)
			(layer "F.SilkS")
		)
		(fp_line
			(start 0.90678 0.4826)
			(end -0.90678 0.4826)
			(stroke
				(width 0.1524)
				(type default)
			)
			(layer "F.SilkS")
		)
		(fp_line
			(start 1.03378 -0.4826)
			(end 1.03378 0.4826)
			(stroke
				(width 0.1524)
				(type default)
			)
			(layer "F.SilkS")
		)
		(fp_line
			(start 1.03378 0.4826)
			(end -0.79248 0.4826)
			(stroke
				(width 0.1524)
				(type default)
			)
			(layer "F.SilkS")
		)
		(fp_line
			(start 1.16078 -0.4826)
			(end 1.16078 0.4826)
			(stroke
				(width 0.1524)
				(type default)
			)
			(layer "F.SilkS")
		)
		(fp_line
			(start 1.16078 0.4826)
			(end -0.64008 0.4826)
			(stroke
				(width 0.1524)
				(type default)
			)
			(layer "F.SilkS")
		)
		(fp_line
			(start -0.499872 -0.249936)
			(end 0.499872 -0.249936)
			(stroke
				(width 0.1)
				(type default)
			)
			(layer "F.Fab")
		)
		(fp_line
			(start -0.499872 0.249936)
			(end -0.499872 -0.249936)
			(stroke
				(width 0.1)
				(type default)
			)
			(layer "F.Fab")
		)
		(fp_line
			(start 0.499872 -0.249936)
			(end 0.499872 0.249936)
			(stroke
				(width 0.1)
				(type default)
			)
			(layer "F.Fab")
		)
		(fp_line
			(start 0.499872 0.249936)
			(end -0.499872 0.249936)
			(stroke
				(width 0.1)
				(type default)
			)
			(layer "F.Fab")
		)
		(pad "A" smd rect
			(at -0.47498 0)
			(size 0.6096 0.7112)
			(layers "F.Cu" "F.Mask" "F.Paste")
			(net "LED_RST_PLD_CPU0_DRAM_GH_N")
		)
		(pad "C" smd rect
			(at 0.47498 0)
			(size 0.6096 0.7112)
			(layers "F.Cu" "F.Mask" "F.Paste")
			(net "LED_RST_PLD_CPU0_DRAM_GH_N_D")
		)
	)
)
